(kicad_pcb
	(version 20260206)
	(generator "pcbnew")
	(generator_version "10.0")
	(general
		(thickness 1.6)
		(legacy_teardrops no)
	)
	(paper "A4")
	(title_block
		(title "Wiwynn_Tioga_Pass_MB.brd")
		(comment 1 "Tioga Pass / footprints 3558-3565 of 4770")
	)
	(layers
		(0 "F.Cu" signal "TOP")
		(4 "In1.Cu" signal "L2GND")
		(6 "In2.Cu" signal "L3")
		(8 "In3.Cu" signal "L4GND")
		(10 "In4.Cu" signal "L5")
		(12 "In5.Cu" signal "L6GND")
		(14 "In6.Cu" signal "L7VCC")
		(16 "In7.Cu" signal "L8VCC")
		(18 "In8.Cu" signal "L9GND")
		(20 "In9.Cu" signal "L10")
		(22 "In10.Cu" signal "L11GND")
		(24 "In11.Cu" signal "L12")
		(26 "In12.Cu" signal "L13GND")
		(2 "B.Cu" signal "BOTTOM")
		(9 "F.Adhes" user "F.Adhesive")
		(11 "B.Adhes" user "B.Adhesive")
		(13 "F.Paste" user "Package Geometry/Pastemask Top")
		(15 "B.Paste" user "Package Geometry/Pastemask Bottom")
		(5 "F.SilkS" user "Ref Des/Silkscreen Top")
		(7 "B.SilkS" user "Ref Des/Silkscreen Bottom")
		(1 "F.Mask" user "Board Geometry/Soldermask Top")
		(3 "B.Mask" user "Board Geometry/Soldermask Bottom")
		(17 "Dwgs.User" user "User.Drawings")
		(19 "Cmts.User" user "User.Comments")
		(21 "Eco1.User" user "User.Eco1")
		(23 "Eco2.User" user "User.Eco2")
		(25 "Edge.Cuts" user "Board Geometry/Outline")
		(27 "Margin" user)
		(31 "F.CrtYd" user "Package Geometry/Place Bound Top")
		(29 "B.CrtYd" user "Package Geometry/Place Bound Bottom")
		(35 "F.Fab" user "Ref Des/Assembly Top")
		(33 "B.Fab" user "Ref Des/Assembly Bottom")
	)
	(footprint ""
		(layer "B.Cu")
		(at 416.9664 -22.987 180)
		(property "Reference" "R25W124"
			(at 0.8382 -0.67818 180)
			(unlocked yes)
			(layer "B.SilkS")
			(effects
				(font
					(size 0.4064 0.254)
					(thickness 0.1524)
				)
				(justify left mirror)
			)
		)
		(property "Value" ""
			(at 0 0 0)
			(layer "B.Fab")
			(effects
				(font
					(size 1.27 1.27)
				)
				(justify mirror)
			)
		)
		(duplicate_pad_numbers_are_jumpers no)
		(fp_poly
			(pts
				(xy 0.2794 -0.1016) (xy -0.2794 -0.1016) (xy -0.2794 0.9906) (xy 0.2794 0.9906)
			)
			(stroke
				(width 0)
				(type default)
			)
			(fill no)
			(layer "B.CrtYd")
		)
		(fp_line
			(start 0.2794 0.9906)
			(end -0.2794 0.9906)
			(stroke
				(width 0.1)
				(type default)
			)
			(layer "B.Fab")
		)
		(fp_line
			(start 0.2794 -0.1016)
			(end 0.2794 0.9906)
			(stroke
				(width 0.1)
				(type default)
			)
			(layer "B.Fab")
		)
		(fp_line
			(start -0.2794 0.9906)
			(end -0.2794 -0.1016)
			(stroke
				(width 0.1)
				(type default)
			)
			(layer "B.Fab")
		)
		(fp_line
			(start -0.2794 -0.1016)
			(end 0.2794 -0.1016)
			(stroke
				(width 0.1)
				(type default)
			)
			(layer "B.Fab")
		)
		(pad "1" smd rect
			(at 0 0)
			(size 0.508 0.508)
			(layers "B.Cu" "B.Mask" "B.Paste")
			(net "BMC_VGA_GREEN")
		)
		(pad "2" smd rect
			(at 0 0.889)
			(size 0.508 0.508)
			(layers "B.Cu" "B.Mask" "B.Paste")
			(net "GND")
		)
		(zone
			(layer "B.Cu")
			(hatch none 0.5)
			(connect_pads
				(clearance 0)
			)
			(min_thickness 0.25)
			(keepout
				(tracks not_allowed)
				(vias allowed)
				(pads allowed)
				(copperpour not_allowed)
				(footprints allowed)
			)
			(placement
				(enabled no)
				(sheetname "")
			)
			(fill
				(thermal_gap 0.5)
				(thermal_bridge_width 0.5)
				(island_removal_mode 0)
			)
			(polygon
				(pts
					(xy 416.7124 -23.622) (xy 417.2204 -23.622) (xy 417.2204 -23.241) (xy 416.7124 -23.241)
				)
			)
		)
		(zone
			(layer "B.Cu")
			(hatch none 0.5)
			(connect_pads
				(clearance 0)
			)
			(min_thickness 0.25)
			(keepout
				(tracks allowed)
				(vias not_allowed)
				(pads allowed)
				(copperpour not_allowed)
				(footprints allowed)
			)
			(placement
				(enabled no)
				(sheetname "")
			)
			(fill
				(thermal_gap 0.5)
				(thermal_bridge_width 0.5)
				(island_removal_mode 0)
			)
			(polygon
				(pts
					(xy 416.7124 -23.241) (xy 417.2204 -23.241) (xy 417.2204 -23.622) (xy 416.7124 -23.622)
				)
			)
		)
	)
	(footprint ""
		(layer "B.Cu")
		(at 417.223194 -38.2905 90)
		(property "Reference" "C25W44"
			(at 0.8382 -0.67818 90)
			(unlocked yes)
			(layer "B.SilkS")
			(effects
				(font
					(size 0.4064 0.254)
					(thickness 0.1524)
				)
				(justify left mirror)
			)
		)
		(property "Value" ""
			(at 0 0 90)
			(layer "B.Fab")
			(effects
				(font
					(size 1.27 1.27)
				)
				(justify mirror)
			)
		)
		(duplicate_pad_numbers_are_jumpers no)
		(fp_poly
			(pts
				(xy -0.3048 -0.1016) (xy -0.3048 0.9906) (xy 0.3048 0.9906) (xy 0.3048 -0.1016)
			)
			(stroke
				(width 0)
				(type default)
			)
			(fill no)
			(layer "B.CrtYd")
		)
		(fp_line
			(start 0.3048 -0.1016)
			(end 0.3048 0.9906)
			(stroke
				(width 0.1)
				(type default)
			)
			(layer "B.Fab")
		)
		(fp_line
			(start -0.3048 -0.1016)
			(end 0.3048 -0.1016)
			(stroke
				(width 0.1)
				(type default)
			)
			(layer "B.Fab")
		)
		(fp_line
			(start 0.3048 0.9906)
			(end -0.3048 0.9906)
			(stroke
				(width 0.1)
				(type default)
			)
			(layer "B.Fab")
		)
		(fp_line
			(start -0.3048 0.9906)
			(end -0.3048 -0.1016)
			(stroke
				(width 0.1)
				(type default)
			)
			(layer "B.Fab")
		)
		(pad "1" smd rect
			(at 0 0 270)
			(size 0.508 0.508)
			(layers "B.Cu" "B.Mask" "B.Paste")
			(net "VCC_D_3V3")
		)
		(pad "2" smd rect
			(at 0 0.889 270)
			(size 0.508 0.508)
			(layers "B.Cu" "B.Mask" "B.Paste")
			(net "GND")
		)
		(zone
			(layer "B.Cu")
			(hatch none 0.5)
			(connect_pads
				(clearance 0)
			)
			(min_thickness 0.25)
			(keepout
				(tracks allowed)
				(vias not_allowed)
				(pads allowed)
				(copperpour not_allowed)
				(footprints allowed)
			)
			(placement
				(enabled no)
				(sheetname "")
			)
			(fill
				(thermal_gap 0.5)
				(thermal_bridge_width 0.5)
				(island_removal_mode 0)
			)
			(polygon
				(pts
					(xy 417.477194 -38.5445) (xy 417.477194 -38.0365) (xy 417.858194 -38.0365) (xy 417.858194 -38.5445)
				)
			)
		)
		(zone
			(layer "B.Cu")
			(hatch none 0.5)
			(connect_pads
				(clearance 0)
			)
			(min_thickness 0.25)
			(keepout
				(tracks not_allowed)
				(vias allowed)
				(pads allowed)
				(copperpour not_allowed)
				(footprints allowed)
			)
			(placement
				(enabled no)
				(sheetname "")
			)
			(fill
				(thermal_gap 0.5)
				(thermal_bridge_width 0.5)
				(island_removal_mode 0)
			)
			(polygon
				(pts
					(xy 417.858194 -38.5445) (xy 417.858194 -38.0365) (xy 417.477194 -38.0365) (xy 417.477194 -38.5445)
				)
			)
		)
	)
	(footprint ""
		(layer "B.Cu")
		(at 272.861532 -8.1534 90)
		(property "Reference" "C5U3"
			(at -1.848866 0.752348 90)
			(unlocked yes)
			(layer "B.SilkS")
			(effects
				(font
					(size 1.27 0.9652)
					(thickness 0.1524)
				)
				(justify mirror)
			)
		)
		(property "Value" ""
			(at 0 0 90)
			(layer "B.Fab")
			(effects
				(font
					(size 1.27 1.27)
				)
				(justify mirror)
			)
		)
		(duplicate_pad_numbers_are_jumpers no)
		(fp_rect
			(start 0.500126 1.598422)
			(end -0.500126 -0.201422)
			(stroke
				(width 0)
				(type default)
			)
			(fill no)
			(layer "B.CrtYd")
		)
		(fp_line
			(start 0.500126 -0.201422)
			(end -0.500126 -0.201422)
			(stroke
				(width 0.1)
				(type default)
			)
			(layer "B.Fab")
		)
		(fp_line
			(start -0.500126 -0.201422)
			(end -0.500126 1.598422)
			(stroke
				(width 0.1)
				(type default)
			)
			(layer "B.Fab")
		)
		(fp_line
			(start 0.500126 1.598422)
			(end 0.500126 -0.201422)
			(stroke
				(width 0.1)
				(type default)
			)
			(layer "B.Fab")
		)
		(fp_line
			(start -0.500126 1.598422)
			(end 0.500126 1.598422)
			(stroke
				(width 0.1)
				(type default)
			)
			(layer "B.Fab")
		)
		(pad "1" smd rect
			(at 0 0)
			(size 0.889 0.9906)
			(layers "B.Cu" "B.Mask" "B.Paste")
			(net "PVDDQ_ABC")
		)
		(pad "2" smd rect
			(at 0 1.397)
			(size 0.889 0.9906)
			(layers "B.Cu" "B.Mask" "B.Paste")
			(net "GND")
		)
		(zone
			(layer "B.Cu")
			(hatch none 0.5)
			(connect_pads
				(clearance 0)
			)
			(min_thickness 0.25)
			(keepout
				(tracks not_allowed)
				(vias allowed)
				(pads allowed)
				(copperpour not_allowed)
				(footprints allowed)
			)
			(placement
				(enabled no)
				(sheetname "")
			)
			(fill
				(thermal_gap 0.5)
				(thermal_bridge_width 0.5)
				(island_removal_mode 0)
			)
			(polygon
				(pts
					(xy 273.814032 -8.6487) (xy 273.306032 -8.6487) (xy 273.306032 -7.6581) (xy 273.814032 -7.6581)
				)
			)
		)
		(zone
			(layer "B.Cu")
			(hatch none 0.5)
			(connect_pads
				(clearance 0)
			)
			(min_thickness 0.25)
			(keepout
				(tracks allowed)
				(vias not_allowed)
				(pads allowed)
				(copperpour not_allowed)
				(footprints allowed)
			)
			(placement
				(enabled no)
				(sheetname "")
			)
			(fill
				(thermal_gap 0.5)
				(thermal_bridge_width 0.5)
				(island_removal_mode 0)
			)
			(polygon
				(pts
					(xy 273.814032 -8.6487) (xy 273.306032 -8.6487) (xy 273.306032 -7.6581) (xy 273.814032 -7.6581)
				)
			)
		)
	)
	(footprint ""
		(layer "B.Cu")
		(at 32.832802 -89.158064 90)
		(property "Reference" "C9N27"
			(at 0 0 90)
			(layer "B.SilkS")
			(hide yes)
			(effects
				(font
					(size 1.27 1.27)
				)
				(justify mirror)
			)
		)
		(property "Value" ""
			(at 0 0 90)
			(layer "B.Fab")
			(effects
				(font
					(size 1.27 1.27)
				)
				(justify mirror)
			)
		)
		(duplicate_pad_numbers_are_jumpers no)
		(fp_poly
			(pts
				(xy 0.7239 -0.2159) (xy -0.7239 -0.2159) (xy -0.7239 1.9939) (xy 0.7239 1.9939)
			)
			(stroke
				(width 0)
				(type default)
			)
			(fill no)
			(layer "B.CrtYd")
		)
		(fp_line
			(start 0.7239 -0.2159)
			(end 0.7239 1.9939)
			(stroke
				(width 0.1)
				(type default)
			)
			(layer "B.Fab")
		)
		(fp_line
			(start -0.7239 -0.2159)
			(end 0.7239 -0.2159)
			(stroke
				(width 0.1)
				(type default)
			)
			(layer "B.Fab")
		)
		(fp_line
			(start 0.7239 1.9939)
			(end -0.7239 1.9939)
			(stroke
				(width 0.1)
				(type default)
			)
			(layer "B.Fab")
		)
		(fp_line
			(start -0.7239 1.9939)
			(end -0.7239 -0.2159)
			(stroke
				(width 0.1)
				(type default)
			)
			(layer "B.Fab")
		)
		(pad "1" smd rect
			(at 0 0 270)
			(size 1.27 1.016)
			(layers "B.Cu" "B.Mask" "B.Paste")
			(net "VR_FET_SW_P12V_STBY_PVCCIN_CPU1")
		)
		(pad "2" smd rect
			(at 0 1.778 270)
			(size 1.27 1.016)
			(layers "B.Cu" "B.Mask" "B.Paste")
			(net "GND")
		)
		(zone
			(layer "B.Cu")
			(hatch none 0.5)
			(connect_pads
				(clearance 0)
			)
			(min_thickness 0.25)
			(keepout
				(tracks not_allowed)
				(vias allowed)
				(pads allowed)
				(copperpour not_allowed)
				(footprints allowed)
			)
			(placement
				(enabled no)
				(sheetname "")
			)
			(fill
				(thermal_gap 0.5)
				(thermal_bridge_width 0.5)
				(island_removal_mode 0)
			)
			(polygon
				(pts
					(xy 33.340802 -89.793064) (xy 33.340802 -88.523064) (xy 34.102802 -88.523064) (xy 34.102802 -89.793064)
				)
			)
		)
	)
	(footprint ""
		(layer "B.Cu")
		(at 253.392432 -145.0086 90)
		(property "Reference" "C5L10"
			(at -1.848866 0.752348 90)
			(unlocked yes)
			(layer "B.SilkS")
			(effects
				(font
					(size 1.27 0.9652)
					(thickness 0.1524)
				)
				(justify mirror)
			)
		)
		(property "Value" ""
			(at 0 0 90)
			(layer "B.Fab")
			(effects
				(font
					(size 1.27 1.27)
				)
				(justify mirror)
			)
		)
		(duplicate_pad_numbers_are_jumpers no)
		(fp_rect
			(start 0.500126 1.598422)
			(end -0.500126 -0.201422)
			(stroke
				(width 0)
				(type default)
			)
			(fill no)
			(layer "B.CrtYd")
		)
		(fp_line
			(start 0.500126 -0.201422)
			(end -0.500126 -0.201422)
			(stroke
				(width 0.1)
				(type default)
			)
			(layer "B.Fab")
		)
		(fp_line
			(start -0.500126 -0.201422)
			(end -0.500126 1.598422)
			(stroke
				(width 0.1)
				(type default)
			)
			(layer "B.Fab")
		)
		(fp_line
			(start 0.500126 1.598422)
			(end 0.500126 -0.201422)
			(stroke
				(width 0.1)
				(type default)
			)
			(layer "B.Fab")
		)
		(fp_line
			(start -0.500126 1.598422)
			(end 0.500126 1.598422)
			(stroke
				(width 0.1)
				(type default)
			)
			(layer "B.Fab")
		)
		(pad "1" smd rect
			(at 0 0)
			(size 0.889 0.9906)
			(layers "B.Cu" "B.Mask" "B.Paste")
			(net "PVDDQ_DEF")
		)
		(pad "2" smd rect
			(at 0 1.397)
			(size 0.889 0.9906)
			(layers "B.Cu" "B.Mask" "B.Paste")
			(net "GND")
		)
		(zone
			(layer "B.Cu")
			(hatch none 0.5)
			(connect_pads
				(clearance 0)
			)
			(min_thickness 0.25)
			(keepout
				(tracks not_allowed)
				(vias allowed)
				(pads allowed)
				(copperpour not_allowed)
				(footprints allowed)
			)
			(placement
				(enabled no)
				(sheetname "")
			)
			(fill
				(thermal_gap 0.5)
				(thermal_bridge_width 0.5)
				(island_removal_mode 0)
			)
			(polygon
				(pts
					(xy 254.344932 -145.5039) (xy 253.836932 -145.5039) (xy 253.836932 -144.5133) (xy 254.344932 -144.5133)
				)
			)
		)
		(zone
			(layer "B.Cu")
			(hatch none 0.5)
			(connect_pads
				(clearance 0)
			)
			(min_thickness 0.25)
			(keepout
				(tracks allowed)
				(vias not_allowed)
				(pads allowed)
				(copperpour not_allowed)
				(footprints allowed)
			)
			(placement
				(enabled no)
				(sheetname "")
			)
			(fill
				(thermal_gap 0.5)
				(thermal_bridge_width 0.5)
				(island_removal_mode 0)
			)
			(polygon
				(pts
					(xy 254.344932 -145.5039) (xy 253.836932 -145.5039) (xy 253.836932 -144.5133) (xy 254.344932 -144.5133)
				)
			)
		)
	)
	(footprint ""
		(layer "B.Cu")
		(at 32.832802 -84.357464 90)
		(property "Reference" "C9P2"
			(at 0 0 90)
			(layer "B.SilkS")
			(hide yes)
			(effects
				(font
					(size 1.27 1.27)
				)
				(justify mirror)
			)
		)
		(property "Value" ""
			(at 0 0 90)
			(layer "B.Fab")
			(effects
				(font
					(size 1.27 1.27)
				)
				(justify mirror)
			)
		)
		(duplicate_pad_numbers_are_jumpers no)
		(fp_poly
			(pts
				(xy 0.7239 -0.2159) (xy -0.7239 -0.2159) (xy -0.7239 1.9939) (xy 0.7239 1.9939)
			)
			(stroke
				(width 0)
				(type default)
			)
			(fill no)
			(layer "B.CrtYd")
		)
		(fp_line
			(start 0.7239 -0.2159)
			(end 0.7239 1.9939)
			(stroke
				(width 0.1)
				(type default)
			)
			(layer "B.Fab")
		)
		(fp_line
			(start -0.7239 -0.2159)
			(end 0.7239 -0.2159)
			(stroke
				(width 0.1)
				(type default)
			)
			(layer "B.Fab")
		)
		(fp_line
			(start 0.7239 1.9939)
			(end -0.7239 1.9939)
			(stroke
				(width 0.1)
				(type default)
			)
			(layer "B.Fab")
		)
		(fp_line
			(start -0.7239 1.9939)
			(end -0.7239 -0.2159)
			(stroke
				(width 0.1)
				(type default)
			)
			(layer "B.Fab")
		)
		(pad "1" smd rect
			(at 0 0 270)
			(size 1.27 1.016)
			(layers "B.Cu" "B.Mask" "B.Paste")
			(net "VR_FET_SW_P12V_STBY_PVCCIN_CPU1")
		)
		(pad "2" smd rect
			(at 0 1.778 270)
			(size 1.27 1.016)
			(layers "B.Cu" "B.Mask" "B.Paste")
			(net "GND")
		)
		(zone
			(layer "B.Cu")
			(hatch none 0.5)
			(connect_pads
				(clearance 0)
			)
			(min_thickness 0.25)
			(keepout
				(tracks not_allowed)
				(vias allowed)
				(pads allowed)
				(copperpour not_allowed)
				(footprints allowed)
			)
			(placement
				(enabled no)
				(sheetname "")
			)
			(fill
				(thermal_gap 0.5)
				(thermal_bridge_width 0.5)
				(island_removal_mode 0)
			)
			(polygon
				(pts
					(xy 33.340802 -84.992464) (xy 33.340802 -83.722464) (xy 34.102802 -83.722464) (xy 34.102802 -84.992464)
				)
			)
		)
	)
	(footprint ""
		(layer "B.Cu")
		(at 446.024 -116.49202)
		(property "Reference" "C1M19"
			(at 0 0 0)
			(layer "B.SilkS")
			(hide yes)
			(effects
				(font
					(size 1.27 1.27)
				)
				(justify mirror)
			)
		)
		(property "Value" ""
			(at 0 0 0)
			(layer "B.Fab")
			(effects
				(font
					(size 1.27 1.27)
				)
				(justify mirror)
			)
		)
		(duplicate_pad_numbers_are_jumpers no)
		(fp_rect
			(start -0.3048 0.9906)
			(end 0.3048 -0.1016)
			(stroke
				(width 0)
				(type default)
			)
			(fill no)
			(layer "B.CrtYd")
		)
		(fp_line
			(start -0.3048 -0.1016)
			(end 0.3048 -0.1016)
			(stroke
				(width 0.1)
				(type default)
			)
			(layer "B.Fab")
		)
		(fp_line
			(start -0.3048 0.9906)
			(end -0.3048 -0.1016)
			(stroke
				(width 0.1)
				(type default)
			)
			(layer "B.Fab")
		)
		(fp_line
			(start 0.3048 -0.1016)
			(end 0.3048 0.9906)
			(stroke
				(width 0.1)
				(type default)
			)
			(layer "B.Fab")
		)
		(fp_line
			(start 0.3048 0.9906)
			(end -0.3048 0.9906)
			(stroke
				(width 0.1)
				(type default)
			)
			(layer "B.Fab")
		)
		(pad "1" smd rect
			(at 0 0 180)
			(size 0.508 0.508)
			(layers "B.Cu" "B.Mask" "B.Paste")
			(net "P3E_CPU0_PE3_OCP_TXN<9>")
		)
		(pad "2" smd rect
			(at 0 0.889 180)
			(size 0.508 0.508)
			(layers "B.Cu" "B.Mask" "B.Paste")
			(net "P3E_OCP_CPU0_PE3_C_TXN<9>")
		)
		(zone
			(layer "B.Cu")
			(hatch none 0.5)
			(connect_pads
				(clearance 0)
			)
			(min_thickness 0.25)
			(keepout
				(tracks allowed)
				(vias not_allowed)
				(pads allowed)
				(copperpour not_allowed)
				(footprints allowed)
			)
			(placement
				(enabled no)
				(sheetname "")
			)
			(fill
				(thermal_gap 0.5)
				(thermal_bridge_width 0.5)
				(island_removal_mode 0)
			)
			(polygon
				(pts
					(xy 445.77 -115.85702) (xy 446.278 -115.85702) (xy 446.278 -116.23802) (xy 445.77 -116.23802)
				)
			)
		)
		(zone
			(layer "B.Cu")
			(hatch none 0.5)
			(connect_pads
				(clearance 0)
			)
			(min_thickness 0.25)
			(keepout
				(tracks not_allowed)
				(vias allowed)
				(pads allowed)
				(copperpour not_allowed)
				(footprints allowed)
			)
			(placement
				(enabled no)
				(sheetname "")
			)
			(fill
				(thermal_gap 0.5)
				(thermal_bridge_width 0.5)
				(island_removal_mode 0)
			)
			(polygon
				(pts
					(xy 445.77 -115.85702) (xy 446.278 -115.85702) (xy 446.278 -116.23802) (xy 445.77 -116.23802)
				)
			)
		)
	)
	(footprint ""
		(layer "B.Cu")
		(at 245.815612 -125.55601 90)
		(property "Reference" "C5M11"
			(at 0 0 90)
			(layer "B.SilkS")
			(hide yes)
			(effects
				(font
					(size 1.27 1.27)
				)
				(justify mirror)
			)
		)
		(property "Value" ""
			(at 0 0 90)
			(layer "B.Fab")
			(effects
				(font
					(size 1.27 1.27)
				)
				(justify mirror)
			)
		)
		(duplicate_pad_numbers_are_jumpers no)
		(fp_rect
			(start 0.500126 1.598422)
			(end -0.500126 -0.201422)
			(stroke
				(width 0)
				(type default)
			)
			(fill no)
			(layer "B.CrtYd")
		)
		(fp_line
			(start 0.500126 -0.201422)
			(end -0.500126 -0.201422)
			(stroke
				(width 0.1)
				(type default)
			)
			(layer "B.Fab")
		)
		(fp_line
			(start -0.500126 -0.201422)
			(end -0.500126 1.598422)
			(stroke
				(width 0.1)
				(type default)
			)
			(layer "B.Fab")
		)
		(fp_line
			(start 0.500126 1.598422)
			(end 0.500126 -0.201422)
			(stroke
				(width 0.1)
				(type default)
			)
			(layer "B.Fab")
		)
		(fp_line
			(start -0.500126 1.598422)
			(end 0.500126 1.598422)
			(stroke
				(width 0.1)
				(type default)
			)
			(layer "B.Fab")
		)
		(pad "1" smd rect
			(at 0 0)
			(size 0.889 0.9906)
			(layers "B.Cu" "B.Mask" "B.Paste")
			(net "PVDDQ_DEF")
		)
		(pad "2" smd rect
			(at 0 1.397)
			(size 0.889 0.9906)
			(layers "B.Cu" "B.Mask" "B.Paste")
			(net "GND")
		)
		(zone
			(layer "B.Cu")
			(hatch none 0.5)
			(connect_pads
				(clearance 0)
			)
			(min_thickness 0.25)
			(keepout
				(tracks not_allowed)
				(vias allowed)
				(pads allowed)
				(copperpour not_allowed)
				(footprints allowed)
			)
			(placement
				(enabled no)
				(sheetname "")
			)
			(fill
				(thermal_gap 0.5)
				(thermal_bridge_width 0.5)
				(island_removal_mode 0)
			)
			(polygon
				(pts
					(xy 246.768112 -126.05131) (xy 246.260112 -126.05131) (xy 246.260112 -125.06071) (xy 246.768112 -125.06071)
				)
			)
		)
		(zone
			(layer "B.Cu")
			(hatch none 0.5)
			(connect_pads
				(clearance 0)
			)
			(min_thickness 0.25)
			(keepout
				(tracks allowed)
				(vias not_allowed)
				(pads allowed)
				(copperpour not_allowed)
				(footprints allowed)
			)
			(placement
				(enabled no)
				(sheetname "")
			)
			(fill
				(thermal_gap 0.5)
				(thermal_bridge_width 0.5)
				(island_removal_mode 0)
			)
			(polygon
				(pts
					(xy 246.768112 -126.05131) (xy 246.260112 -126.05131) (xy 246.260112 -125.06071) (xy 246.768112 -125.06071)
				)
			)
		)
	)
)
